# T6G (Grand Teton) — schematic netlist excerpt (pin names and nets, part order shuffled) for the footprints in the layout excerpt that follows; sources: Cadence DE-HDL packaged netlist, KiCad conversion of 04192023_DAF0TMB3IC0_F0TG_MB_C_brd_V02_OCP.brd

PR152  Q_RES  1K 1% CHIP  pkg 0402LF  page 210 : A = P3V3_AUX ; B = PVDDCR_SOC_P1_EN_GD
PC374_1  Q_CAP  0.1UF 25V 10% X7R  pkg 0402  page 218 : A = PVDDCR_CPU1_P1_VCCS ; B = GND

(kicad_pcb
	(version 20260206)
	(generator "pcbnew")
	(generator_version "10.0")
	(general
		(thickness 1.6)
		(legacy_teardrops no)
	)
	(paper "A4")
	(title_block
		(title "04192023_DAF0TMB3IC0_F0TG_MB_C_brd_V02_OCP.brd")
		(comment 1 "Grand Teton / footprints 506-507 of 8354")
	)
	(layers
		(0 "F.Cu" signal "TOP")
		(4 "In1.Cu" signal "GND")
		(6 "In2.Cu" signal "IN1")
		(8 "In3.Cu" signal "GND1")
		(10 "In4.Cu" signal "IN2")
		(12 "In5.Cu" signal "GND2")
		(14 "In6.Cu" signal "IN3")
		(16 "In7.Cu" signal "GND3")
		(18 "In8.Cu" signal "VCC")
		(20 "In9.Cu" signal "VCC1")
		(22 "In10.Cu" signal "GND4")
		(24 "In11.Cu" signal "IN4")
		(26 "In12.Cu" signal "GND5")
		(28 "In13.Cu" signal "IN5")
		(30 "In14.Cu" signal "GND6")
		(32 "In15.Cu" signal "IN6")
		(34 "In16.Cu" signal "GND7")
		(2 "B.Cu" signal "BOTTOM")
		(9 "F.Adhes" user "F.Adhesive")
		(11 "B.Adhes" user "B.Adhesive")
		(13 "F.Paste" user "Package Geometry/Pastemask Top")
		(15 "B.Paste" user "Package Geometry/Pastemask Bottom")
		(5 "F.SilkS" user "Ref Des/Silkscreen Top")
		(7 "B.SilkS" user "Ref Des/Silkscreen Bottom")
		(1 "F.Mask" user "Board Geometry/Soldermask Top")
		(3 "B.Mask" user "Board Geometry/Soldermask Bottom")
		(17 "Dwgs.User" user "User.Drawings")
		(19 "Cmts.User" user "User.Comments")
		(21 "Eco1.User" user "User.Eco1")
		(23 "Eco2.User" user "User.Eco2")
		(25 "Edge.Cuts" user "Board Geometry/Outline")
		(27 "Margin" user)
		(31 "F.CrtYd" user "Package Geometry/Place Bound Top")
		(29 "B.CrtYd" user "Package Geometry/Place Bound Bottom")
		(35 "F.Fab" user "Ref Des/Assembly Top")
		(33 "B.Fab" user "Ref Des/Assembly Bottom")
	)
	(footprint ""
		(layer "F.Cu")
		(at 84.42833 -339.835998 90)
		(property "Reference" "PC374_1"
			(at 0 0 90)
			(layer "F.SilkS")
			(hide yes)
			(effects
				(font
					(size 1.27 1.27)
				)
			)
		)
		(property "Value" ""
			(at 0 0 90)
			(layer "F.Fab")
			(effects
				(font
					(size 1.27 1.27)
				)
			)
		)
		(duplicate_pad_numbers_are_jumpers no)
		(fp_line
			(start 0.7874 -0.4064)
			(end 0.7874 0.4064)
			(stroke
				(width 0.1524)
				(type default)
			)
			(layer "F.SilkS")
		)
		(fp_line
			(start -0.7874 -0.4064)
			(end 0.7874 -0.4064)
			(stroke
				(width 0.1524)
				(type default)
			)
			(layer "F.SilkS")
		)
		(fp_line
			(start 0.7874 0.4064)
			(end -0.7874 0.4064)
			(stroke
				(width 0.1524)
				(type default)
			)
			(layer "F.SilkS")
		)
		(fp_line
			(start -0.7874 0.4064)
			(end -0.7874 -0.4064)
			(stroke
				(width 0.1524)
				(type default)
			)
			(layer "F.SilkS")
		)
		(fp_line
			(start -0.12065 -0.305054)
			(end -0.12065 -0.2794)
			(stroke
				(width 0.1)
				(type default)
			)
			(layer "F.Fab")
		)
		(fp_line
			(start -0.67945 -0.305054)
			(end -0.12065 -0.305054)
			(stroke
				(width 0.1)
				(type default)
			)
			(layer "F.Fab")
		)
		(fp_line
			(start 0.67945 -0.3048)
			(end 0.67945 0.3048)
			(stroke
				(width 0.1)
				(type default)
			)
			(layer "F.Fab")
		)
		(fp_line
			(start 0.12065 -0.3048)
			(end 0.67945 -0.3048)
			(stroke
				(width 0.1)
				(type default)
			)
			(layer "F.Fab")
		)
		(fp_line
			(start 0.12065 -0.2794)
			(end 0.12065 -0.3048)
			(stroke
				(width 0.1)
				(type default)
			)
			(layer "F.Fab")
		)
		(fp_line
			(start -0.12065 -0.2794)
			(end 0.12065 -0.2794)
			(stroke
				(width 0.1)
				(type default)
			)
			(layer "F.Fab")
		)
		(fp_line
			(start 0.120396 0.2794)
			(end -0.12065 0.2794)
			(stroke
				(width 0.1)
				(type default)
			)
			(layer "F.Fab")
		)
		(fp_line
			(start -0.12065 0.2794)
			(end -0.12065 0.3048)
			(stroke
				(width 0.1)
				(type default)
			)
			(layer "F.Fab")
		)
		(fp_line
			(start 0.67945 0.3048)
			(end 0.120396 0.3048)
			(stroke
				(width 0.1)
				(type default)
			)
			(layer "F.Fab")
		)
		(fp_line
			(start 0.120396 0.3048)
			(end 0.120396 0.2794)
			(stroke
				(width 0.1)
				(type default)
			)
			(layer "F.Fab")
		)
		(fp_line
			(start -0.12065 0.3048)
			(end -0.67945 0.3048)
			(stroke
				(width 0.1)
				(type default)
			)
			(layer "F.Fab")
		)
		(fp_line
			(start -0.67945 0.3048)
			(end -0.67945 -0.305054)
			(stroke
				(width 0.1)
				(type default)
			)
			(layer "F.Fab")
		)
		(pad "1" smd circle
			(at -0.40005 0 90)
			(size 0 0)
			(layers "F.Cu" "F.Mask" "F.Paste")
			(net "PVDDCR_CPU1_P1_VCCS")
		)
		(pad "2" smd circle
			(at 0.40005 0 90)
			(size 0 0)
			(layers "F.Cu" "F.Mask" "F.Paste")
			(net "GND")
		)
	)
	(footprint ""
		(layer "F.Cu")
		(at 104.843834 -135.290052 90)
		(property "Reference" "PR152"
			(at 0 0 90)
			(layer "F.SilkS")
			(hide yes)
			(effects
				(font
					(size 1.27 1.27)
				)
			)
		)
		(property "Value" ""
			(at 0 0 90)
			(layer "F.Fab")
			(effects
				(font
					(size 1.27 1.27)
				)
			)
		)
		(duplicate_pad_numbers_are_jumpers no)
		(fp_line
			(start 0.7874 -0.4064)
			(end 0.7874 0.4064)
			(stroke
				(width 0.1524)
				(type default)
			)
			(layer "F.SilkS")
		)
		(fp_line
			(start -0.7874 -0.4064)
			(end 0.7874 -0.4064)
			(stroke
				(width 0.1524)
				(type default)
			)
			(layer "F.SilkS")
		)
		(fp_line
			(start 0.7874 0.4064)
			(end -0.7874 0.4064)
			(stroke
				(width 0.1524)
				(type default)
			)
			(layer "F.SilkS")
		)
		(fp_line
			(start -0.7874 0.4064)
			(end -0.7874 -0.4064)
			(stroke
				(width 0.1524)
				(type default)
			)
			(layer "F.SilkS")
		)
		(fp_line
			(start -0.12065 -0.305054)
			(end -0.12065 -0.2794)
			(stroke
				(width 0.1)
				(type default)
			)
			(layer "F.Fab")
		)
		(fp_line
			(start -0.67945 -0.305054)
			(end -0.12065 -0.305054)
			(stroke
				(width 0.1)
				(type default)
			)
			(layer "F.Fab")
		)
		(fp_line
			(start 0.67945 -0.3048)
			(end 0.67945 0.3048)
			(stroke
				(width 0.1)
				(type default)
			)
			(layer "F.Fab")
		)
		(fp_line
			(start 0.12065 -0.3048)
			(end 0.67945 -0.3048)
			(stroke
				(width 0.1)
				(type default)
			)
			(layer "F.Fab")
		)
		(fp_line
			(start 0.12065 -0.2794)
			(end 0.12065 -0.3048)
			(stroke
				(width 0.1)
				(type default)
			)
			(layer "F.Fab")
		)
		(fp_line
			(start -0.12065 -0.2794)
			(end 0.12065 -0.2794)
			(stroke
				(width 0.1)
				(type default)
			)
			(layer "F.Fab")
		)
		(fp_line
			(start 0.120396 0.2794)
			(end -0.12065 0.2794)
			(stroke
				(width 0.1)
				(type default)
			)
			(layer "F.Fab")
		)
		(fp_line
			(start -0.12065 0.2794)
			(end -0.12065 0.3048)
			(stroke
				(width 0.1)
				(type default)
			)
			(layer "F.Fab")
		)
		(fp_line
			(start 0.67945 0.3048)
			(end 0.120396 0.3048)
			(stroke
				(width 0.1)
				(type default)
			)
			(layer "F.Fab")
		)
		(fp_line
			(start 0.120396 0.3048)
			(end 0.120396 0.2794)
			(stroke
				(width 0.1)
				(type default)
			)
			(layer "F.Fab")
		)
		(fp_line
			(start -0.12065 0.3048)
			(end -0.67945 0.3048)
			(stroke
				(width 0.1)
				(type default)
			)
			(layer "F.Fab")
		)
		(fp_line
			(start -0.67945 0.3048)
			(end -0.67945 -0.305054)
			(stroke
				(width 0.1)
				(type default)
			)
			(layer "F.Fab")
		)
		(pad "1" smd circle
			(at -0.40005 0 90)
			(size 0 0)
			(layers "F.Cu" "F.Mask" "F.Paste")
			(net "P3V3_AUX")
		)
		(pad "2" smd circle
			(at 0.40005 0 90)
			(size 0 0)
			(layers "F.Cu" "F.Mask" "F.Paste")
			(net "PVDDCR_SOC_P1_EN_GD")
		)
	)
)
